(kicad_pcb
	(version 20260206)
	(generator "pcbnew")
	(generator_version "10.0")
	(general
		(thickness 1.6)
		(legacy_teardrops no)
	)
	(paper "A4")
	(title_block
		(title "v1-chassis-manager — T6M_CM_d_v01_1031_1645.brd")
		(comment 1 "Open CloudServer (Microsoft) / footprints 1389-1398 of 2512")
	)
	(layers
		(0 "F.Cu" signal "TOP")
		(4 "In1.Cu" signal "GND1")
		(6 "In2.Cu" signal "IN1")
		(8 "In3.Cu" signal "VCC1")
		(10 "In4.Cu" signal "VCC2")
		(12 "In5.Cu" signal "GND2")
		(14 "In6.Cu" signal "IN2")
		(16 "In7.Cu" signal "IN3")
		(18 "In8.Cu" signal "GND3")
		(2 "B.Cu" signal "BOTTOM")
		(9 "F.Adhes" user "F.Adhesive")
		(11 "B.Adhes" user "B.Adhesive")
		(13 "F.Paste" user "Package Geometry/Pastemask Top")
		(15 "B.Paste" user "Package Geometry/Pastemask Bottom")
		(5 "F.SilkS" user "Ref Des/Silkscreen Top")
		(7 "B.SilkS" user "Ref Des/Silkscreen Bottom")
		(1 "F.Mask" user "Board Geometry/Soldermask Top")
		(3 "B.Mask" user "Board Geometry/Soldermask Bottom")
		(17 "Dwgs.User" user "User.Drawings")
		(19 "Cmts.User" user "User.Comments")
		(21 "Eco1.User" user "User.Eco1")
		(23 "Eco2.User" user "User.Eco2")
		(25 "Edge.Cuts" user "Board Geometry/Outline")
		(27 "Margin" user)
		(31 "F.CrtYd" user "Package Geometry/Place Bound Top")
		(29 "B.CrtYd" user "Package Geometry/Place Bound Bottom")
		(35 "F.Fab" user "Ref Des/Assembly Top")
		(33 "B.Fab" user "Ref Des/Assembly Bottom")
	)
	(footprint ""
		(layer "F.Cu")
		(at 80.907128 -141.347952)
		(property "Reference" "C840"
			(at -2.42062 3.949192 0)
			(unlocked yes)
			(layer "F.SilkS")
			(effects
				(font
					(size 0.635 0.4064)
					(thickness 0.1524)
				)
				(justify left)
			)
		)
		(property "Value" ""
			(at 0 0 0)
			(layer "F.Fab")
			(effects
				(font
					(size 1.27 1.27)
				)
			)
		)
		(duplicate_pad_numbers_are_jumpers no)
		(fp_line
			(start -0.7874 -0.4064)
			(end 0.7874 -0.4064)
			(stroke
				(width 0.1524)
				(type default)
			)
			(layer "F.SilkS")
		)
		(fp_line
			(start -0.7874 0.4064)
			(end -0.7874 -0.4064)
			(stroke
				(width 0.1524)
				(type default)
			)
			(layer "F.SilkS")
		)
		(fp_line
			(start 0 0.381)
			(end 0 -0.381)
			(stroke
				(width 0.1524)
				(type default)
			)
			(layer "F.SilkS")
		)
		(fp_line
			(start 0.7874 -0.4064)
			(end 0.7874 0.4064)
			(stroke
				(width 0.1524)
				(type default)
			)
			(layer "F.SilkS")
		)
		(fp_line
			(start 0.7874 0.4064)
			(end -0.7874 0.4064)
			(stroke
				(width 0.1524)
				(type default)
			)
			(layer "F.SilkS")
		)
		(fp_poly
			(pts
				(xy -0.5334 0.254) (xy -0.635 0.254) (xy -0.635 0.2286) (xy -0.635 -0.254) (xy -0.5334 -0.254) (xy -0.5334 -0.2794)
				(xy 0.5334 -0.2794) (xy 0.5334 -0.254) (xy 0.635 -0.254) (xy 0.635 0.254) (xy 0.5334 0.254) (xy 0.5334 0.2794)
				(xy -0.508 0.2794) (xy -0.5334 0.2794)
			)
			(stroke
				(width 0)
				(type default)
			)
			(fill no)
			(layer "F.CrtYd")
		)
		(pad "1" smd rect
			(at 0.40005 0)
			(size 0.4572 0.508)
			(layers "F.Cu" "F.Mask" "F.Paste")
			(net "P1V26_BMC_NODE1")
		)
		(pad "2" smd rect
			(at -0.40005 0)
			(size 0.4572 0.508)
			(layers "F.Cu" "F.Mask" "F.Paste")
			(net "GND")
		)
	)
	(footprint ""
		(layer "F.Cu")
		(at 8.67156 -138.620246 -90)
		(property "Reference" "R1302"
			(at 4.242054 4.105402 90)
			(unlocked yes)
			(layer "F.SilkS")
			(effects
				(font
					(size 0.7874 0.5842)
					(thickness 0.1524)
				)
				(justify left)
			)
		)
		(property "Value" ""
			(at 0 0 270)
			(layer "F.Fab")
			(effects
				(font
					(size 1.27 1.27)
				)
			)
		)
		(duplicate_pad_numbers_are_jumpers no)
		(fp_line
			(start -0.7874 0.4064)
			(end -0.7874 -0.4064)
			(stroke
				(width 0.1524)
				(type default)
			)
			(layer "F.SilkS")
		)
		(fp_line
			(start 0.7874 0.4064)
			(end -0.7874 0.4064)
			(stroke
				(width 0.1524)
				(type default)
			)
			(layer "F.SilkS")
		)
		(fp_line
			(start -0.7874 -0.4064)
			(end 0.7874 -0.4064)
			(stroke
				(width 0.1524)
				(type default)
			)
			(layer "F.SilkS")
		)
		(fp_line
			(start 0.7874 -0.4064)
			(end 0.7874 0.4064)
			(stroke
				(width 0.1524)
				(type default)
			)
			(layer "F.SilkS")
		)
		(fp_poly
			(pts
				(xy -0.508 0.2794) (xy -0.508 0.2286) (xy -0.635 0.2286) (xy -0.635 -0.254) (xy -0.5334 -0.254)
				(xy -0.5334 -0.2794) (xy 0.5334 -0.2794) (xy 0.5334 -0.254) (xy 0.635 -0.254) (xy 0.635 0.254) (xy 0.5334 0.254)
				(xy 0.5334 0.2794)
			)
			(stroke
				(width 0)
				(type default)
			)
			(fill no)
			(layer "F.CrtYd")
		)
		(pad "1" smd rect
			(at 0.40005 0 270)
			(size 0.4572 0.508)
			(layers "F.Cu" "F.Mask" "F.Paste")
			(net "P3V3_NODE1")
		)
		(pad "2" smd rect
			(at -0.40005 0 270)
			(size 0.4572 0.508)
			(layers "F.Cu" "F.Mask" "F.Paste")
			(net "N54310543")
		)
	)
	(footprint ""
		(layer "F.Cu")
		(at 169.792396 -60.66663)
		(property "Reference" "R271"
			(at -0.427736 -2.219452 0)
			(unlocked yes)
			(layer "F.SilkS")
			(effects
				(font
					(size 0.7874 0.5842)
					(thickness 0.1524)
				)
				(justify left)
			)
		)
		(property "Value" ""
			(at 0 0 0)
			(layer "F.Fab")
			(effects
				(font
					(size 1.27 1.27)
				)
			)
		)
		(duplicate_pad_numbers_are_jumpers no)
		(fp_line
			(start -0.7874 -0.4064)
			(end 0.7874 -0.4064)
			(stroke
				(width 0.1524)
				(type default)
			)
			(layer "F.SilkS")
		)
		(fp_line
			(start -0.7874 0.4064)
			(end -0.7874 -0.4064)
			(stroke
				(width 0.1524)
				(type default)
			)
			(layer "F.SilkS")
		)
		(fp_line
			(start 0.7874 -0.4064)
			(end 0.7874 0.4064)
			(stroke
				(width 0.1524)
				(type default)
			)
			(layer "F.SilkS")
		)
		(fp_line
			(start 0.7874 0.4064)
			(end -0.7874 0.4064)
			(stroke
				(width 0.1524)
				(type default)
			)
			(layer "F.SilkS")
		)
		(fp_poly
			(pts
				(xy -0.508 0.2794) (xy -0.508 0.2286) (xy -0.635 0.2286) (xy -0.635 -0.254) (xy -0.5334 -0.254)
				(xy -0.5334 -0.2794) (xy 0.5334 -0.2794) (xy 0.5334 -0.254) (xy 0.635 -0.254) (xy 0.635 0.254) (xy 0.5334 0.254)
				(xy 0.5334 0.2794)
			)
			(stroke
				(width 0)
				(type default)
			)
			(fill no)
			(layer "F.CrtYd")
		)
		(pad "1" smd rect
			(at 0.40005 0)
			(size 0.4572 0.508)
			(layers "F.Cu" "F.Mask" "F.Paste")
			(net "USB3_L_DN")
		)
		(pad "2" smd rect
			(at -0.40005 0)
			(size 0.4572 0.508)
			(layers "F.Cu" "F.Mask" "F.Paste")
			(net "USB3_DN")
		)
	)
	(footprint ""
		(layer "F.Cu")
		(at 144.789652 -150.19655)
		(property "Reference" "R278"
			(at -0.319786 17.243044 0)
			(unlocked yes)
			(layer "F.SilkS")
			(effects
				(font
					(size 0.7874 0.5842)
					(thickness 0.1524)
				)
				(justify left)
			)
		)
		(property "Value" ""
			(at 0 0 0)
			(layer "F.Fab")
			(effects
				(font
					(size 1.27 1.27)
				)
			)
		)
		(duplicate_pad_numbers_are_jumpers no)
		(fp_line
			(start -0.7874 -0.4064)
			(end 0.7874 -0.4064)
			(stroke
				(width 0.1524)
				(type default)
			)
			(layer "F.SilkS")
		)
		(fp_line
			(start -0.7874 0.4064)
			(end -0.7874 -0.4064)
			(stroke
				(width 0.1524)
				(type default)
			)
			(layer "F.SilkS")
		)
		(fp_line
			(start 0.7874 -0.4064)
			(end 0.7874 0.4064)
			(stroke
				(width 0.1524)
				(type default)
			)
			(layer "F.SilkS")
		)
		(fp_line
			(start 0.7874 0.4064)
			(end -0.7874 0.4064)
			(stroke
				(width 0.1524)
				(type default)
			)
			(layer "F.SilkS")
		)
		(fp_poly
			(pts
				(xy -0.508 0.2794) (xy -0.508 0.2286) (xy -0.635 0.2286) (xy -0.635 -0.254) (xy -0.5334 -0.254)
				(xy -0.5334 -0.2794) (xy 0.5334 -0.2794) (xy 0.5334 -0.254) (xy 0.635 -0.254) (xy 0.635 0.254) (xy 0.5334 0.254)
				(xy 0.5334 0.2794)
			)
			(stroke
				(width 0)
				(type default)
			)
			(fill no)
			(layer "F.CrtYd")
		)
		(pad "1" smd rect
			(at 0.40005 0)
			(size 0.4572 0.508)
			(layers "F.Cu" "F.Mask" "F.Paste")
			(net "GND")
		)
		(pad "2" smd rect
			(at -0.40005 0)
			(size 0.4572 0.508)
			(layers "F.Cu" "F.Mask" "F.Paste")
			(net "PCIE_SW_P1_CTCDIS")
		)
	)
	(footprint ""
		(layer "F.Cu")
		(at 137.593578 -62.736222 180)
		(property "Reference" "R510"
			(at 1.277874 -4.45643 0)
			(unlocked yes)
			(layer "F.SilkS")
			(effects
				(font
					(size 0.7874 0.5842)
					(thickness 0.1524)
				)
				(justify left)
			)
		)
		(property "Value" ""
			(at 0 0 180)
			(layer "F.Fab")
			(effects
				(font
					(size 1.27 1.27)
				)
			)
		)
		(duplicate_pad_numbers_are_jumpers no)
		(fp_line
			(start 0.7874 0.4064)
			(end -0.7874 0.4064)
			(stroke
				(width 0.1524)
				(type default)
			)
			(layer "F.SilkS")
		)
		(fp_line
			(start 0.7874 -0.4064)
			(end 0.7874 0.4064)
			(stroke
				(width 0.1524)
				(type default)
			)
			(layer "F.SilkS")
		)
		(fp_line
			(start -0.7874 0.4064)
			(end -0.7874 -0.4064)
			(stroke
				(width 0.1524)
				(type default)
			)
			(layer "F.SilkS")
		)
		(fp_line
			(start -0.7874 -0.4064)
			(end 0.7874 -0.4064)
			(stroke
				(width 0.1524)
				(type default)
			)
			(layer "F.SilkS")
		)
		(fp_poly
			(pts
				(xy -0.508 0.2794) (xy -0.508 0.2286) (xy -0.635 0.2286) (xy -0.635 -0.254) (xy -0.5334 -0.254)
				(xy -0.5334 -0.2794) (xy 0.5334 -0.2794) (xy 0.5334 -0.254) (xy 0.635 -0.254) (xy 0.635 0.254) (xy 0.5334 0.254)
				(xy 0.5334 0.2794)
			)
			(stroke
				(width 0)
				(type default)
			)
			(fill no)
			(layer "F.CrtYd")
		)
		(pad "1" smd rect
			(at 0.40005 0 180)
			(size 0.4572 0.508)
			(layers "F.Cu" "F.Mask" "F.Paste")
			(net "GND")
		)
		(pad "2" smd rect
			(at -0.40005 0 180)
			(size 0.4572 0.508)
			(layers "F.Cu" "F.Mask" "F.Paste")
			(net "SATA_NODE1_GPIO1")
		)
	)
	(footprint ""
		(layer "F.Cu")
		(at 36.093908 -19.453352 180)
		(property "Reference" "C143"
			(at 1.836928 -1.289558 0)
			(unlocked yes)
			(layer "F.SilkS")
			(effects
				(font
					(size 0.7874 0.5842)
					(thickness 0.1524)
				)
				(justify left)
			)
		)
		(property "Value" ""
			(at 0 0 180)
			(layer "F.Fab")
			(effects
				(font
					(size 1.27 1.27)
				)
			)
		)
		(duplicate_pad_numbers_are_jumpers no)
		(fp_line
			(start 0.7874 0.4064)
			(end -0.7874 0.4064)
			(stroke
				(width 0.1524)
				(type default)
			)
			(layer "F.SilkS")
		)
		(fp_line
			(start 0.7874 -0.4064)
			(end 0.7874 0.4064)
			(stroke
				(width 0.1524)
				(type default)
			)
			(layer "F.SilkS")
		)
		(fp_line
			(start 0 0.381)
			(end 0 -0.381)
			(stroke
				(width 0.1524)
				(type default)
			)
			(layer "F.SilkS")
		)
		(fp_line
			(start -0.7874 0.4064)
			(end -0.7874 -0.4064)
			(stroke
				(width 0.1524)
				(type default)
			)
			(layer "F.SilkS")
		)
		(fp_line
			(start -0.7874 -0.4064)
			(end 0.7874 -0.4064)
			(stroke
				(width 0.1524)
				(type default)
			)
			(layer "F.SilkS")
		)
		(fp_poly
			(pts
				(xy -0.5334 0.254) (xy -0.635 0.254) (xy -0.635 0.2286) (xy -0.635 -0.254) (xy -0.5334 -0.254) (xy -0.5334 -0.2794)
				(xy 0.5334 -0.2794) (xy 0.5334 -0.254) (xy 0.635 -0.254) (xy 0.635 0.254) (xy 0.5334 0.254) (xy 0.5334 0.2794)
				(xy -0.508 0.2794) (xy -0.5334 0.2794)
			)
			(stroke
				(width 0)
				(type default)
			)
			(fill no)
			(layer "F.CrtYd")
		)
		(pad "1" smd rect
			(at 0.40005 0 180)
			(size 0.4572 0.508)
			(layers "F.Cu" "F.Mask" "F.Paste")
			(net "P1V5_NODE1_DDR3_VREF0_D")
		)
		(pad "2" smd rect
			(at -0.40005 0 180)
			(size 0.4572 0.508)
			(layers "F.Cu" "F.Mask" "F.Paste")
			(net "GND")
		)
	)
	(footprint ""
		(layer "F.Cu")
		(at 19.684746 -119.127524)
		(property "Reference" "PL6"
			(at -4.056634 3.772154 90)
			(unlocked yes)
			(layer "F.SilkS")
			(effects
				(font
					(size 0.7874 0.5842)
					(thickness 0.1524)
				)
				(justify left)
			)
		)
		(property "Value" ""
			(at 0 0 0)
			(layer "F.Fab")
			(effects
				(font
					(size 1.27 1.27)
				)
			)
		)
		(duplicate_pad_numbers_are_jumpers no)
		(fp_line
			(start -3.350006 -4.1656)
			(end 3.350006 -4.1656)
			(stroke
				(width 0.1524)
				(type default)
			)
			(layer "F.SilkS")
		)
		(fp_line
			(start -3.350006 4.1656)
			(end -3.350006 -4.1656)
			(stroke
				(width 0.1524)
				(type default)
			)
			(layer "F.SilkS")
		)
		(fp_line
			(start 3.350006 -4.1656)
			(end 3.350006 4.1656)
			(stroke
				(width 0.1524)
				(type default)
			)
			(layer "F.SilkS")
		)
		(fp_line
			(start 3.350006 4.1656)
			(end -3.350006 4.1656)
			(stroke
				(width 0.1524)
				(type default)
			)
			(layer "F.SilkS")
		)
		(fp_poly
			(pts
				(xy -3.350006 -3.64998) (xy -1.7018 -3.64998) (xy -1.7018 -4.05257) (xy 1.7018 -4.05257) (xy 1.7018 -3.64998)
				(xy 3.350006 -3.64998) (xy 3.350006 3.64998) (xy 1.7018 3.64998) (xy 1.7018 4.05257) (xy -1.7018 4.05257)
				(xy -1.7018 3.64998) (xy -3.350006 3.64998)
			)
			(stroke
				(width 0)
				(type default)
			)
			(fill no)
			(layer "F.CrtYd")
		)
		(fp_line
			(start -3.350006 -3.64998)
			(end 3.350006 -3.64998)
			(stroke
				(width 0.1)
				(type default)
			)
			(layer "F.Fab")
		)
		(fp_line
			(start -3.350006 3.64998)
			(end -3.350006 -3.64998)
			(stroke
				(width 0.1)
				(type default)
			)
			(layer "F.Fab")
		)
		(fp_line
			(start 3.350006 -3.64998)
			(end 3.350006 3.64998)
			(stroke
				(width 0.1)
				(type default)
			)
			(layer "F.Fab")
		)
		(fp_line
			(start 3.350006 3.64998)
			(end -3.350006 3.64998)
			(stroke
				(width 0.1)
				(type default)
			)
			(layer "F.Fab")
		)
		(pad "1" smd rect
			(at 0 -2.92481 270)
			(size 2.15392 3.302)
			(layers "F.Cu" "F.Mask" "F.Paste")
			(net "SW_P1V05_NODE1_PH")
		)
		(pad "2" smd rect
			(at 0 2.92481 270)
			(size 2.15392 3.302)
			(layers "F.Cu" "F.Mask" "F.Paste")
			(net "P1V05_NODE1")
		)
	)
	(footprint ""
		(layer "F.Cu")
		(at 35.85464 -14.23797 -90)
		(property "Reference" "PR35"
			(at 0.977392 3.54711 90)
			(unlocked yes)
			(layer "F.SilkS")
			(effects
				(font
					(size 0.7874 0.5842)
					(thickness 0.1524)
				)
				(justify left)
			)
		)
		(property "Value" ""
			(at 0 0 270)
			(layer "F.Fab")
			(effects
				(font
					(size 1.27 1.27)
				)
			)
		)
		(duplicate_pad_numbers_are_jumpers no)
		(fp_line
			(start -0.7874 0.4064)
			(end -0.7874 -0.4064)
			(stroke
				(width 0.1524)
				(type default)
			)
			(layer "F.SilkS")
		)
		(fp_line
			(start 0.7874 0.4064)
			(end -0.7874 0.4064)
			(stroke
				(width 0.1524)
				(type default)
			)
			(layer "F.SilkS")
		)
		(fp_line
			(start -0.7874 -0.4064)
			(end 0.7874 -0.4064)
			(stroke
				(width 0.1524)
				(type default)
			)
			(layer "F.SilkS")
		)
		(fp_line
			(start 0.7874 -0.4064)
			(end 0.7874 0.4064)
			(stroke
				(width 0.1524)
				(type default)
			)
			(layer "F.SilkS")
		)
		(fp_poly
			(pts
				(xy -0.508 0.2794) (xy -0.508 0.2286) (xy -0.635 0.2286) (xy -0.635 -0.254) (xy -0.5334 -0.254)
				(xy -0.5334 -0.2794) (xy 0.5334 -0.2794) (xy 0.5334 -0.254) (xy 0.635 -0.254) (xy 0.635 0.254) (xy 0.5334 0.254)
				(xy 0.5334 0.2794)
			)
			(stroke
				(width 0)
				(type default)
			)
			(fill no)
			(layer "F.CrtYd")
		)
		(pad "1" smd rect
			(at 0.40005 0 270)
			(size 0.4572 0.508)
			(layers "F.Cu" "F.Mask" "F.Paste")
			(net "VSENSE_PV_VDDR_NODE1_P")
		)
		(pad "2" smd rect
			(at -0.40005 0 270)
			(size 0.4572 0.508)
			(layers "F.Cu" "F.Mask" "F.Paste")
			(net "PV_VDDR_NODE1")
		)
	)
	(footprint ""
		(layer "F.Cu")
		(at 25.999948 -62.799976)
		(property "Reference" "H3"
			(at 2.062734 -2.494788 0)
			(unlocked yes)
			(layer "F.SilkS")
			(effects
				(font
					(size 0.7874 0.5842)
					(thickness 0.1524)
				)
				(justify left)
			)
		)
		(property "Value" ""
			(at 0 0 0)
			(layer "F.Fab")
			(effects
				(font
					(size 1.27 1.27)
				)
			)
		)
		(duplicate_pad_numbers_are_jumpers no)
		(fp_circle
			(center 0 0)
			(end 2.3114 0)
			(stroke
				(width 0.1524)
				(type default)
			)
			(fill no)
			(layer "F.SilkS")
		)
		(fp_circle
			(center 0 0)
			(end 2.3114 0)
			(stroke
				(width 0.1524)
				(type default)
			)
			(fill no)
			(layer "B.SilkS")
		)
		(fp_poly
			(pts
				(arc
					(start 0 1.4986)
					(mid 0 -1.4986)
					(end 0 1.4986)
				)
			)
			(stroke
				(width 0)
				(type default)
			)
			(fill no)
			(layer "F.CrtYd")
		)
		(pad "" np_thru_hole circle
			(at 0 0)
			(size 2.9972 2.9972)
			(drill 2.9972)
			(layers "*.Cu" "*.Mask")
			(clearance 0.381)
			(thermal_gap 0.381)
		)
		(zone
			(layers "F.Cu" "B.Cu" "In1.Cu" "In2.Cu" "In3.Cu" "In4.Cu" "In5.Cu" "In6.Cu"
				"In7.Cu" "In8.Cu"
			)
			(hatch none 0.5)
			(connect_pads
				(clearance 0)
			)
			(min_thickness 0.25)
			(keepout
				(tracks not_allowed)
				(vias allowed)
				(pads allowed)
				(copperpour not_allowed)
				(footprints allowed)
			)
			(placement
				(enabled no)
				(sheetname "")
			)
			(fill
				(thermal_gap 0.5)
				(thermal_bridge_width 0.5)
				(island_removal_mode 0)
			)
			(polygon
				(pts
					(arc
						(start 25.999948 -60.793376)
						(mid 25.999948 -64.806576)
						(end 25.999948 -60.793376)
					)
				)
			)
		)
	)
	(footprint ""
		(layer "F.Cu")
		(at 14.052804 -163.557712 180)
		(property "Reference" "R1275"
			(at 1.786128 2.286 0)
			(unlocked yes)
			(layer "F.SilkS")
			(effects
				(font
					(size 0.7874 0.5842)
					(thickness 0.1524)
				)
				(justify left)
			)
		)
		(property "Value" ""
			(at 0 0 180)
			(layer "F.Fab")
			(effects
				(font
					(size 1.27 1.27)
				)
			)
		)
		(duplicate_pad_numbers_are_jumpers no)
		(fp_line
			(start 0.7874 0.4064)
			(end -0.7874 0.4064)
			(stroke
				(width 0.1524)
				(type default)
			)
			(layer "F.SilkS")
		)
		(fp_line
			(start 0.7874 -0.4064)
			(end 0.7874 0.4064)
			(stroke
				(width 0.1524)
				(type default)
			)
			(layer "F.SilkS")
		)
		(fp_line
			(start -0.7874 0.4064)
			(end -0.7874 -0.4064)
			(stroke
				(width 0.1524)
				(type default)
			)
			(layer "F.SilkS")
		)
		(fp_line
			(start -0.7874 -0.4064)
			(end 0.7874 -0.4064)
			(stroke
				(width 0.1524)
				(type default)
			)
			(layer "F.SilkS")
		)
		(fp_poly
			(pts
				(xy -0.508 0.2794) (xy -0.508 0.2286) (xy -0.635 0.2286) (xy -0.635 -0.254) (xy -0.5334 -0.254)
				(xy -0.5334 -0.2794) (xy 0.5334 -0.2794) (xy 0.5334 -0.254) (xy 0.635 -0.254) (xy 0.635 0.254) (xy 0.5334 0.254)
				(xy 0.5334 0.2794)
			)
			(stroke
				(width 0)
				(type default)
			)
			(fill no)
			(layer "F.CrtYd")
		)
		(pad "1" smd rect
			(at 0.40005 0 180)
			(size 0.4572 0.508)
			(layers "F.Cu" "F.Mask" "F.Paste")
			(net "N54065132")
		)
		(pad "2" smd rect
			(at -0.40005 0 180)
			(size 0.4572 0.508)
			(layers "F.Cu" "F.Mask" "F.Paste")
			(net "LAN1_P3_R")
		)
	)
)
